#ISCELL
  mstr_misc dns *
  *
#ISCELL
  pure_quanta quanta_title_block_c *
  *
#CELL
  pure_quanta q_res *
  page192_i1
#CELL
  pure_quanta q_res *
  page192_i11
#ISCELL
  logical_power universal_power *
  page192_i12
#ISCELL
  standard offpage *
  page192_i13
#ISCELL
  standard offpage *
  page192_i14
#ISCELL
  standard offpage *
  page192_i16
#CELL
  pure_quanta q_res *
  page192_i17
#CELL
  pure_quanta q_res *
  page192_i18
#ISCELL
  logical_power universal_power *
  page192_i2
#CELL
  pure_quanta q_res *
  page192_i23
#CELL
  pure_quanta q_res *
  page192_i24
#ISCELL
  logical_power universal_power *
  page192_i25
#CELL
  pure_quanta q_res *
  page192_i26
#ISCELL
  standard offpage *
  page192_i28
#ISCELL
  standard offpage *
  page192_i29
#ISCELL
  standard offpage *
  page192_i3
#ISCELL
  standard offpage *
  page192_i30
#ISCELL
  standard offpage *
  page192_i33
#ISCELL
  standard offpage *
  page192_i34
#ISCELL
  logical_power universal_power *
  page192_i39
#CELL
  pure_quanta q_res *
  page192_i4
#CELL
  pure_quanta q_res *
  page192_i41
#CELL
  pure_quanta q_res *
  page192_i42
#ISCELL
  standard offpage *
  page192_i44
#ISCELL
  standard offpage *
  page192_i45
#ISCELL
  logical_power universal_power *
  page192_i49
#ISCELL
  standard offpage *
  page192_i5
#CELL
  pure_quanta q_res *
  page192_i50
#CELL
  pure_quanta q_res *
  page192_i51
#ISCELL
  standard offpage *
  page192_i53
#ISCELL
  standard offpage *
  page192_i54
#ISCELL
  logical_power universal_power *
  page192_i58
#CELL
  pure_quanta q_res *
  page192_i59
#CELL
  pure_quanta q_res *
  page192_i6
#CELL
  pure_quanta q_res *
  page192_i60
#ISCELL
  standard offpage *
  page192_i61
#CELL
  pure_quanta q_res *
  page192_i62
#ISCELL
  standard offpage *
  page192_i64
#ISCELL
  logical_power universal_power *
  page192_i65
#CELL
  pure_quanta q_res *
  page192_i66
#ISCELL
  logical_power universal_power *
  page192_i67
#ISCELL
  standard offpage *
  page192_i68
#CELL
  pure_quanta q_res *
  page192_i69
#ISCELL
  standard offpage *
  page192_i7
#ISCELL
  standard offpage *
  page192_i71
#CELL
  pure_quanta q_res *
  page192_i72
#ISCELL
  standard offpage *
  page192_i74
#CELL
  pure_quanta q_res *
  page192_i75
#CELL
  pure_quanta q_res *
  page192_i8
#ISCELL
  standard offpage *
  page192_i9
